(kicad_pcb
	(version 20260206)
	(generator "pcbnew")
	(generator_version "10.0")
	(general
		(thickness 1.6)
		(legacy_teardrops no)
	)
	(paper "A4")
	(title_block
		(title "01162023_DA0F0TEBIF0_F0T_Expander_BD_F_brd_V02_OCP.brd")
		(comment 1 "Grand Teton / footprints 4698-4704 of 9728")
	)
	(layers
		(0 "F.Cu" signal "TOP")
		(4 "In1.Cu" signal "GND")
		(6 "In2.Cu" signal "VCC")
		(8 "In3.Cu" signal "VCC1")
		(10 "In4.Cu" signal "GND1")
		(12 "In5.Cu" signal "IN1")
		(14 "In6.Cu" signal "GND2")
		(16 "In7.Cu" signal "IN2")
		(18 "In8.Cu" signal "GND3")
		(20 "In9.Cu" signal "IN3")
		(22 "In10.Cu" signal "GND4")
		(24 "In11.Cu" signal "IN4")
		(26 "In12.Cu" signal "GND5")
		(28 "In13.Cu" signal "IN5")
		(30 "In14.Cu" signal "GND6")
		(32 "In15.Cu" signal "IN6")
		(34 "In16.Cu" signal "GND7")
		(2 "B.Cu" signal "BOTTOM")
		(9 "F.Adhes" user "F.Adhesive")
		(11 "B.Adhes" user "B.Adhesive")
		(13 "F.Paste" user "Package Geometry/Pastemask Top")
		(15 "B.Paste" user "Package Geometry/Pastemask Bottom")
		(5 "F.SilkS" user "Ref Des/Silkscreen Top")
		(7 "B.SilkS" user "Ref Des/Silkscreen Bottom")
		(1 "F.Mask" user "Board Geometry/Soldermask Top")
		(3 "B.Mask" user "Board Geometry/Soldermask Bottom")
		(17 "Dwgs.User" user "User.Drawings")
		(19 "Cmts.User" user "User.Comments")
		(21 "Eco1.User" user "User.Eco1")
		(23 "Eco2.User" user "User.Eco2")
		(25 "Edge.Cuts" user "Board Geometry/Outline")
		(27 "Margin" user)
		(31 "F.CrtYd" user "Package Geometry/Place Bound Top")
		(29 "B.CrtYd" user "Package Geometry/Place Bound Bottom")
		(35 "F.Fab" user "Ref Des/Assembly Top")
		(33 "B.Fab" user "Ref Des/Assembly Bottom")
	)
	(footprint ""
		(layer "F.Cu")
		(at 393.546838 -37.47516)
		(property "Reference" "R6122"
			(at 0 0 0)
			(layer "F.SilkS")
			(hide yes)
			(effects
				(font
					(size 1.27 1.27)
				)
			)
		)
		(property "Value" ""
			(at 0 0 0)
			(layer "F.Fab")
			(effects
				(font
					(size 1.27 1.27)
				)
			)
		)
		(duplicate_pad_numbers_are_jumpers no)
		(fp_line
			(start -0.7874 -0.4064)
			(end 0.7874 -0.4064)
			(stroke
				(width 0.1524)
				(type default)
			)
			(layer "F.SilkS")
		)
		(fp_line
			(start -0.7874 0.4064)
			(end -0.7874 -0.4064)
			(stroke
				(width 0.1524)
				(type default)
			)
			(layer "F.SilkS")
		)
		(fp_line
			(start 0.7874 -0.4064)
			(end 0.7874 0.4064)
			(stroke
				(width 0.1524)
				(type default)
			)
			(layer "F.SilkS")
		)
		(fp_line
			(start 0.7874 0.4064)
			(end -0.7874 0.4064)
			(stroke
				(width 0.1524)
				(type default)
			)
			(layer "F.SilkS")
		)
		(fp_line
			(start -0.67945 -0.305054)
			(end -0.12065 -0.305054)
			(stroke
				(width 0.1)
				(type default)
			)
			(layer "F.Fab")
		)
		(fp_line
			(start -0.67945 0.3048)
			(end -0.67945 -0.305054)
			(stroke
				(width 0.1)
				(type default)
			)
			(layer "F.Fab")
		)
		(fp_line
			(start -0.12065 -0.305054)
			(end -0.12065 -0.2794)
			(stroke
				(width 0.1)
				(type default)
			)
			(layer "F.Fab")
		)
		(fp_line
			(start -0.12065 -0.2794)
			(end 0.12065 -0.2794)
			(stroke
				(width 0.1)
				(type default)
			)
			(layer "F.Fab")
		)
		(fp_line
			(start -0.12065 0.2794)
			(end -0.12065 0.3048)
			(stroke
				(width 0.1)
				(type default)
			)
			(layer "F.Fab")
		)
		(fp_line
			(start -0.12065 0.3048)
			(end -0.67945 0.3048)
			(stroke
				(width 0.1)
				(type default)
			)
			(layer "F.Fab")
		)
		(fp_line
			(start 0.120396 0.2794)
			(end -0.12065 0.2794)
			(stroke
				(width 0.1)
				(type default)
			)
			(layer "F.Fab")
		)
		(fp_line
			(start 0.120396 0.3048)
			(end 0.120396 0.2794)
			(stroke
				(width 0.1)
				(type default)
			)
			(layer "F.Fab")
		)
		(fp_line
			(start 0.12065 -0.3048)
			(end 0.67945 -0.3048)
			(stroke
				(width 0.1)
				(type default)
			)
			(layer "F.Fab")
		)
		(fp_line
			(start 0.12065 -0.2794)
			(end 0.12065 -0.3048)
			(stroke
				(width 0.1)
				(type default)
			)
			(layer "F.Fab")
		)
		(fp_line
			(start 0.67945 -0.3048)
			(end 0.67945 0.3048)
			(stroke
				(width 0.1)
				(type default)
			)
			(layer "F.Fab")
		)
		(fp_line
			(start 0.67945 0.3048)
			(end 0.120396 0.3048)
			(stroke
				(width 0.1)
				(type default)
			)
			(layer "F.Fab")
		)
		(pad "1" smd circle
			(at -0.40005 0)
			(size 0 0)
			(layers "F.Cu" "F.Mask" "F.Paste")
			(net "P3V3_SSD14")
		)
		(pad "2" smd circle
			(at 0.40005 0)
			(size 0 0)
			(layers "F.Cu" "F.Mask" "F.Paste")
			(net "P3V3_SSD14_PG_G1")
		)
	)
	(footprint ""
		(layer "F.Cu")
		(at 213.730332 -223.382586 180)
		(property "Reference" "R4882"
			(at 0 0 180)
			(layer "F.SilkS")
			(hide yes)
			(effects
				(font
					(size 1.27 1.27)
				)
			)
		)
		(property "Value" ""
			(at 0 0 180)
			(layer "F.Fab")
			(effects
				(font
					(size 1.27 1.27)
				)
			)
		)
		(duplicate_pad_numbers_are_jumpers no)
		(fp_line
			(start 0.7874 0.4064)
			(end -0.7874 0.4064)
			(stroke
				(width 0.1524)
				(type default)
			)
			(layer "F.SilkS")
		)
		(fp_line
			(start 0.7874 -0.4064)
			(end 0.7874 0.4064)
			(stroke
				(width 0.1524)
				(type default)
			)
			(layer "F.SilkS")
		)
		(fp_line
			(start -0.7874 0.4064)
			(end -0.7874 -0.4064)
			(stroke
				(width 0.1524)
				(type default)
			)
			(layer "F.SilkS")
		)
		(fp_line
			(start -0.7874 -0.4064)
			(end 0.7874 -0.4064)
			(stroke
				(width 0.1524)
				(type default)
			)
			(layer "F.SilkS")
		)
		(fp_line
			(start 0.67945 0.3048)
			(end 0.120396 0.3048)
			(stroke
				(width 0.1)
				(type default)
			)
			(layer "F.Fab")
		)
		(fp_line
			(start 0.67945 -0.3048)
			(end 0.67945 0.3048)
			(stroke
				(width 0.1)
				(type default)
			)
			(layer "F.Fab")
		)
		(fp_line
			(start 0.12065 -0.2794)
			(end 0.12065 -0.3048)
			(stroke
				(width 0.1)
				(type default)
			)
			(layer "F.Fab")
		)
		(fp_line
			(start 0.12065 -0.3048)
			(end 0.67945 -0.3048)
			(stroke
				(width 0.1)
				(type default)
			)
			(layer "F.Fab")
		)
		(fp_line
			(start 0.120396 0.3048)
			(end 0.120396 0.2794)
			(stroke
				(width 0.1)
				(type default)
			)
			(layer "F.Fab")
		)
		(fp_line
			(start 0.120396 0.2794)
			(end -0.12065 0.2794)
			(stroke
				(width 0.1)
				(type default)
			)
			(layer "F.Fab")
		)
		(fp_line
			(start -0.12065 0.3048)
			(end -0.67945 0.3048)
			(stroke
				(width 0.1)
				(type default)
			)
			(layer "F.Fab")
		)
		(fp_line
			(start -0.12065 0.2794)
			(end -0.12065 0.3048)
			(stroke
				(width 0.1)
				(type default)
			)
			(layer "F.Fab")
		)
		(fp_line
			(start -0.12065 -0.2794)
			(end 0.12065 -0.2794)
			(stroke
				(width 0.1)
				(type default)
			)
			(layer "F.Fab")
		)
		(fp_line
			(start -0.12065 -0.305054)
			(end -0.12065 -0.2794)
			(stroke
				(width 0.1)
				(type default)
			)
			(layer "F.Fab")
		)
		(fp_line
			(start -0.67945 0.3048)
			(end -0.67945 -0.305054)
			(stroke
				(width 0.1)
				(type default)
			)
			(layer "F.Fab")
		)
		(fp_line
			(start -0.67945 -0.305054)
			(end -0.12065 -0.305054)
			(stroke
				(width 0.1)
				(type default)
			)
			(layer "F.Fab")
		)
		(pad "1" smd circle
			(at -0.40005 0 180)
			(size 0 0)
			(layers "F.Cu" "F.Mask" "F.Paste")
			(net "SMB_MB_I3C_ISO_SDA")
		)
		(pad "2" smd circle
			(at 0.40005 0 180)
			(size 0 0)
			(layers "F.Cu" "F.Mask" "F.Paste")
			(net "P3V3_AUX")
		)
	)
	(footprint ""
		(layer "F.Cu")
		(at 179.777644 -114.267742)
		(property "Reference" "R191"
			(at 0 0 0)
			(layer "F.SilkS")
			(hide yes)
			(effects
				(font
					(size 1.27 1.27)
				)
			)
		)
		(property "Value" ""
			(at 0 0 0)
			(layer "F.Fab")
			(effects
				(font
					(size 1.27 1.27)
				)
			)
		)
		(duplicate_pad_numbers_are_jumpers no)
		(fp_line
			(start -0.7874 -0.4064)
			(end 0.7874 -0.4064)
			(stroke
				(width 0.1524)
				(type default)
			)
			(layer "F.SilkS")
		)
		(fp_line
			(start -0.7874 0.4064)
			(end -0.7874 -0.4064)
			(stroke
				(width 0.1524)
				(type default)
			)
			(layer "F.SilkS")
		)
		(fp_line
			(start 0.7874 -0.4064)
			(end 0.7874 0.4064)
			(stroke
				(width 0.1524)
				(type default)
			)
			(layer "F.SilkS")
		)
		(fp_line
			(start 0.7874 0.4064)
			(end -0.7874 0.4064)
			(stroke
				(width 0.1524)
				(type default)
			)
			(layer "F.SilkS")
		)
		(fp_line
			(start -0.67945 -0.305054)
			(end -0.12065 -0.305054)
			(stroke
				(width 0.1)
				(type default)
			)
			(layer "F.Fab")
		)
		(fp_line
			(start -0.67945 0.3048)
			(end -0.67945 -0.305054)
			(stroke
				(width 0.1)
				(type default)
			)
			(layer "F.Fab")
		)
		(fp_line
			(start -0.12065 -0.305054)
			(end -0.12065 -0.2794)
			(stroke
				(width 0.1)
				(type default)
			)
			(layer "F.Fab")
		)
		(fp_line
			(start -0.12065 -0.2794)
			(end 0.12065 -0.2794)
			(stroke
				(width 0.1)
				(type default)
			)
			(layer "F.Fab")
		)
		(fp_line
			(start -0.12065 0.2794)
			(end -0.12065 0.3048)
			(stroke
				(width 0.1)
				(type default)
			)
			(layer "F.Fab")
		)
		(fp_line
			(start -0.12065 0.3048)
			(end -0.67945 0.3048)
			(stroke
				(width 0.1)
				(type default)
			)
			(layer "F.Fab")
		)
		(fp_line
			(start 0.120396 0.2794)
			(end -0.12065 0.2794)
			(stroke
				(width 0.1)
				(type default)
			)
			(layer "F.Fab")
		)
		(fp_line
			(start 0.120396 0.3048)
			(end 0.120396 0.2794)
			(stroke
				(width 0.1)
				(type default)
			)
			(layer "F.Fab")
		)
		(fp_line
			(start 0.12065 -0.3048)
			(end 0.67945 -0.3048)
			(stroke
				(width 0.1)
				(type default)
			)
			(layer "F.Fab")
		)
		(fp_line
			(start 0.12065 -0.2794)
			(end 0.12065 -0.3048)
			(stroke
				(width 0.1)
				(type default)
			)
			(layer "F.Fab")
		)
		(fp_line
			(start 0.67945 -0.3048)
			(end 0.67945 0.3048)
			(stroke
				(width 0.1)
				(type default)
			)
			(layer "F.Fab")
		)
		(fp_line
			(start 0.67945 0.3048)
			(end 0.120396 0.3048)
			(stroke
				(width 0.1)
				(type default)
			)
			(layer "F.Fab")
		)
		(pad "1" smd circle
			(at -0.40005 0)
			(size 0 0)
			(layers "F.Cu" "F.Mask" "F.Paste")
			(net "RST_SMB_NIC3_MUX_ISO_N")
		)
		(pad "2" smd circle
			(at 0.40005 0)
			(size 0 0)
			(layers "F.Cu" "F.Mask" "F.Paste")
			(net "GND")
		)
	)
	(footprint ""
		(layer "F.Cu")
		(at 241.64671 -154.256994)
		(property "Reference" "PC810"
			(at 0 0 0)
			(layer "F.SilkS")
			(hide yes)
			(effects
				(font
					(size 1.27 1.27)
				)
			)
		)
		(property "Value" ""
			(at 0 0 0)
			(layer "F.Fab")
			(effects
				(font
					(size 1.27 1.27)
				)
			)
		)
		(duplicate_pad_numbers_are_jumpers no)
		(fp_line
			(start -1.2954 -0.5842)
			(end 1.2954 -0.5842)
			(stroke
				(width 0.1524)
				(type default)
			)
			(layer "F.SilkS")
		)
		(fp_line
			(start -1.2954 0.5842)
			(end -1.2954 -0.5842)
			(stroke
				(width 0.1524)
				(type default)
			)
			(layer "F.SilkS")
		)
		(fp_line
			(start 1.2954 -0.5842)
			(end 1.2954 0.5842)
			(stroke
				(width 0.1524)
				(type default)
			)
			(layer "F.SilkS")
		)
		(fp_line
			(start 1.2954 0.5842)
			(end -1.2954 0.5842)
			(stroke
				(width 0.1524)
				(type default)
			)
			(layer "F.SilkS")
		)
		(fp_line
			(start -1.1938 -0.4064)
			(end -0.8636 -0.4064)
			(stroke
				(width 0.1)
				(type default)
			)
			(layer "F.Fab")
		)
		(fp_line
			(start -1.1938 0.4064)
			(end -1.1938 -0.4064)
			(stroke
				(width 0.1)
				(type default)
			)
			(layer "F.Fab")
		)
		(fp_line
			(start -0.8636 -0.4572)
			(end 0.8636 -0.4572)
			(stroke
				(width 0.1)
				(type default)
			)
			(layer "F.Fab")
		)
		(fp_line
			(start -0.8636 -0.4064)
			(end -0.8636 -0.4572)
			(stroke
				(width 0.1)
				(type default)
			)
			(layer "F.Fab")
		)
		(fp_line
			(start -0.8636 0.4064)
			(end -1.1938 0.4064)
			(stroke
				(width 0.1)
				(type default)
			)
			(layer "F.Fab")
		)
		(fp_line
			(start -0.8636 0.4572)
			(end -0.8636 0.4064)
			(stroke
				(width 0.1)
				(type default)
			)
			(layer "F.Fab")
		)
		(fp_line
			(start 0.8636 -0.4572)
			(end 0.8636 -0.4064)
			(stroke
				(width 0.1)
				(type default)
			)
			(layer "F.Fab")
		)
		(fp_line
			(start 0.8636 -0.4064)
			(end 1.1938 -0.4064)
			(stroke
				(width 0.1)
				(type default)
			)
			(layer "F.Fab")
		)
		(fp_line
			(start 0.8636 0.4064)
			(end 0.8636 0.4572)
			(stroke
				(width 0.1)
				(type default)
			)
			(layer "F.Fab")
		)
		(fp_line
			(start 0.8636 0.4572)
			(end -0.8636 0.4572)
			(stroke
				(width 0.1)
				(type default)
			)
			(layer "F.Fab")
		)
		(fp_line
			(start 1.1938 -0.4064)
			(end 1.1938 0.4064)
			(stroke
				(width 0.1)
				(type default)
			)
			(layer "F.Fab")
		)
		(fp_line
			(start 1.1938 0.4064)
			(end 0.8636 0.4064)
			(stroke
				(width 0.1)
				(type default)
			)
			(layer "F.Fab")
		)
		(pad "1" smd rect
			(at -0.7366 0 270)
			(size 0.7112 0.8128)
			(layers "F.Cu" "F.Mask" "F.Paste")
			(net "GND")
		)
		(pad "2" smd rect
			(at 0.7366 0 270)
			(size 0.7112 0.8128)
			(layers "F.Cu" "F.Mask" "F.Paste")
			(net "P12V_NIC4_CO_AVIN_PD")
		)
	)
	(footprint ""
		(layer "F.Cu")
		(at 264.611358 -283.643832 -90)
		(property "Reference" "R4585"
			(at 0 0 270)
			(layer "F.SilkS")
			(hide yes)
			(effects
				(font
					(size 1.27 1.27)
				)
			)
		)
		(property "Value" ""
			(at 0 0 270)
			(layer "F.Fab")
			(effects
				(font
					(size 1.27 1.27)
				)
			)
		)
		(duplicate_pad_numbers_are_jumpers no)
		(fp_line
			(start -0.7874 0.4064)
			(end -0.7874 -0.4064)
			(stroke
				(width 0.1524)
				(type default)
			)
			(layer "F.SilkS")
		)
		(fp_line
			(start 0.7874 0.4064)
			(end -0.7874 0.4064)
			(stroke
				(width 0.1524)
				(type default)
			)
			(layer "F.SilkS")
		)
		(fp_line
			(start -0.7874 -0.4064)
			(end 0.7874 -0.4064)
			(stroke
				(width 0.1524)
				(type default)
			)
			(layer "F.SilkS")
		)
		(fp_line
			(start 0.7874 -0.4064)
			(end 0.7874 0.4064)
			(stroke
				(width 0.1524)
				(type default)
			)
			(layer "F.SilkS")
		)
		(fp_line
			(start -0.67945 0.3048)
			(end -0.67945 -0.305054)
			(stroke
				(width 0.1)
				(type default)
			)
			(layer "F.Fab")
		)
		(fp_line
			(start -0.12065 0.3048)
			(end -0.67945 0.3048)
			(stroke
				(width 0.1)
				(type default)
			)
			(layer "F.Fab")
		)
		(fp_line
			(start 0.120396 0.3048)
			(end 0.120396 0.2794)
			(stroke
				(width 0.1)
				(type default)
			)
			(layer "F.Fab")
		)
		(fp_line
			(start 0.67945 0.3048)
			(end 0.120396 0.3048)
			(stroke
				(width 0.1)
				(type default)
			)
			(layer "F.Fab")
		)
		(fp_line
			(start -0.12065 0.2794)
			(end -0.12065 0.3048)
			(stroke
				(width 0.1)
				(type default)
			)
			(layer "F.Fab")
		)
		(fp_line
			(start 0.120396 0.2794)
			(end -0.12065 0.2794)
			(stroke
				(width 0.1)
				(type default)
			)
			(layer "F.Fab")
		)
		(fp_line
			(start -0.12065 -0.2794)
			(end 0.12065 -0.2794)
			(stroke
				(width 0.1)
				(type default)
			)
			(layer "F.Fab")
		)
		(fp_line
			(start 0.12065 -0.2794)
			(end 0.12065 -0.3048)
			(stroke
				(width 0.1)
				(type default)
			)
			(layer "F.Fab")
		)
		(fp_line
			(start 0.12065 -0.3048)
			(end 0.67945 -0.3048)
			(stroke
				(width 0.1)
				(type default)
			)
			(layer "F.Fab")
		)
		(fp_line
			(start 0.67945 -0.3048)
			(end 0.67945 0.3048)
			(stroke
				(width 0.1)
				(type default)
			)
			(layer "F.Fab")
		)
		(fp_line
			(start -0.67945 -0.305054)
			(end -0.12065 -0.305054)
			(stroke
				(width 0.1)
				(type default)
			)
			(layer "F.Fab")
		)
		(fp_line
			(start -0.12065 -0.305054)
			(end -0.12065 -0.2794)
			(stroke
				(width 0.1)
				(type default)
			)
			(layer "F.Fab")
		)
		(pad "1" smd circle
			(at -0.40005 0 270)
			(size 0 0)
			(layers "F.Cu" "F.Mask" "F.Paste")
			(net "PCEPLL7_VDDA18_PEX2")
		)
		(pad "2" smd circle
			(at 0.40005 0 270)
			(size 0 0)
			(layers "F.Cu" "F.Mask" "F.Paste")
			(net "PCEPLL7_VDDA18_PEX2_R")
		)
	)
	(footprint ""
		(layer "F.Cu")
		(at 281.221942 -350.098614 90)
		(property "Reference" "C602"
			(at 0 0 90)
			(layer "F.SilkS")
			(hide yes)
			(effects
				(font
					(size 1.27 1.27)
				)
			)
		)
		(property "Value" ""
			(at 0 0 90)
			(layer "F.Fab")
			(effects
				(font
					(size 1.27 1.27)
				)
			)
		)
		(duplicate_pad_numbers_are_jumpers no)
		(fp_line
			(start 0.299974 -0.150114)
			(end 0.299974 0.150114)
			(stroke
				(width 0.1)
				(type default)
			)
			(layer "F.Fab")
		)
		(fp_line
			(start -0.299974 -0.150114)
			(end 0.299974 -0.150114)
			(stroke
				(width 0.1)
				(type default)
			)
			(layer "F.Fab")
		)
		(fp_line
			(start 0.299974 0.150114)
			(end -0.299974 0.150114)
			(stroke
				(width 0.1)
				(type default)
			)
			(layer "F.Fab")
		)
		(fp_line
			(start -0.299974 0.150114)
			(end -0.299974 -0.150114)
			(stroke
				(width 0.1)
				(type default)
			)
			(layer "F.Fab")
		)
		(pad "1" smd rect
			(at -0.2667 0 90)
			(size 0.3048 0.381)
			(layers "F.Cu" "F.Mask" "F.Paste")
			(net "P5E_PEX2_STN7_TX_DN<118>")
		)
		(pad "2" smd rect
			(at 0.2667 0 90)
			(size 0.3048 0.381)
			(layers "F.Cu" "F.Mask" "F.Paste")
			(net "P5E_PEX2_STN7_TX_C_DN<118>")
		)
	)
	(footprint ""
		(layer "F.Cu")
		(at 204.591158 -84.675472)
		(property "Reference" "R4330"
			(at 0 0 0)
			(layer "F.SilkS")
			(hide yes)
			(effects
				(font
					(size 1.27 1.27)
				)
			)
		)
		(property "Value" ""
			(at 0 0 0)
			(layer "F.Fab")
			(effects
				(font
					(size 1.27 1.27)
				)
			)
		)
		(duplicate_pad_numbers_are_jumpers no)
		(fp_line
			(start -0.7874 -0.4064)
			(end 0.7874 -0.4064)
			(stroke
				(width 0.1524)
				(type default)
			)
			(layer "F.SilkS")
		)
		(fp_line
			(start -0.7874 0.4064)
			(end -0.7874 -0.4064)
			(stroke
				(width 0.1524)
				(type default)
			)
			(layer "F.SilkS")
		)
		(fp_line
			(start 0.7874 -0.4064)
			(end 0.7874 0.4064)
			(stroke
				(width 0.1524)
				(type default)
			)
			(layer "F.SilkS")
		)
		(fp_line
			(start 0.7874 0.4064)
			(end -0.7874 0.4064)
			(stroke
				(width 0.1524)
				(type default)
			)
			(layer "F.SilkS")
		)
		(fp_line
			(start -0.67945 -0.305054)
			(end -0.12065 -0.305054)
			(stroke
				(width 0.1)
				(type default)
			)
			(layer "F.Fab")
		)
		(fp_line
			(start -0.67945 0.3048)
			(end -0.67945 -0.305054)
			(stroke
				(width 0.1)
				(type default)
			)
			(layer "F.Fab")
		)
		(fp_line
			(start -0.12065 -0.305054)
			(end -0.12065 -0.2794)
			(stroke
				(width 0.1)
				(type default)
			)
			(layer "F.Fab")
		)
		(fp_line
			(start -0.12065 -0.2794)
			(end 0.12065 -0.2794)
			(stroke
				(width 0.1)
				(type default)
			)
			(layer "F.Fab")
		)
		(fp_line
			(start -0.12065 0.2794)
			(end -0.12065 0.3048)
			(stroke
				(width 0.1)
				(type default)
			)
			(layer "F.Fab")
		)
		(fp_line
			(start -0.12065 0.3048)
			(end -0.67945 0.3048)
			(stroke
				(width 0.1)
				(type default)
			)
			(layer "F.Fab")
		)
		(fp_line
			(start 0.120396 0.2794)
			(end -0.12065 0.2794)
			(stroke
				(width 0.1)
				(type default)
			)
			(layer "F.Fab")
		)
		(fp_line
			(start 0.120396 0.3048)
			(end 0.120396 0.2794)
			(stroke
				(width 0.1)
				(type default)
			)
			(layer "F.Fab")
		)
		(fp_line
			(start 0.12065 -0.3048)
			(end 0.67945 -0.3048)
			(stroke
				(width 0.1)
				(type default)
			)
			(layer "F.Fab")
		)
		(fp_line
			(start 0.12065 -0.2794)
			(end 0.12065 -0.3048)
			(stroke
				(width 0.1)
				(type default)
			)
			(layer "F.Fab")
		)
		(fp_line
			(start 0.67945 -0.3048)
			(end 0.67945 0.3048)
			(stroke
				(width 0.1)
				(type default)
			)
			(layer "F.Fab")
		)
		(fp_line
			(start 0.67945 0.3048)
			(end 0.120396 0.3048)
			(stroke
				(width 0.1)
				(type default)
			)
			(layer "F.Fab")
		)
		(pad "1" smd circle
			(at -0.40005 0)
			(size 0 0)
			(layers "F.Cu" "F.Mask" "F.Paste")
			(net "P3V3_AUX")
		)
		(pad "2" smd circle
			(at 0.40005 0)
			(size 0 0)
			(layers "F.Cu" "F.Mask" "F.Paste")
			(net "SSD0_LED_R")
		)
	)
)
